# S9S_MB_2U (Grand Teton) — schematic netlist excerpt (pin names and nets, part order shuffled) for the footprints in the layout excerpt that follows; sources: Cadence DE-HDL packaged netlist, KiCad conversion of 03242023_DA0F0TMBIJ0_F0T_Motherboard_J_brd_V01_OCP.brd

Q86  MOSFET_NCH_DUAL  PJT138K IC  pkg SOT363XD  page 254
  S1  = GND
  G1  = PWRGD_PVCCINFAON_CPU1
  D2  = LED_PWRGD_PVNN_MAIN_CPU1_D
  S2  = GND
  G2  = PWRGD_PVNN_MAIN_CPU1
  D1  = LED_PWRGD_PVCCINFAON_CPU1_D

U207  74LVC1G17GW  IC  pkg TSSOP5  page 161
  NC  = NC
  A  = RST_HP_OCP_V3_2_N
  GND  = GND
  Y  = RST_OCP_V3_2_BUF_N
  VCC  = P3V3_AUX

(kicad_pcb
	(version 20260206)
	(generator "pcbnew")
	(generator_version "10.0")
	(general
		(thickness 1.6)
		(legacy_teardrops no)
	)
	(paper "A4")
	(title_block
		(title "03242023_DA0F0TMBIJ0_F0T_Motherboard_J_brd_V01_OCP.brd")
		(comment 1 "Grand Teton / footprints 1145-1146 of 6105")
	)
	(layers
		(0 "F.Cu" signal "TOP")
		(4 "In1.Cu" signal "GND")
		(6 "In2.Cu" signal "IN1")
		(8 "In3.Cu" signal "GND1")
		(10 "In4.Cu" signal "IN2")
		(12 "In5.Cu" signal "GND2")
		(14 "In6.Cu" signal "IN3")
		(16 "In7.Cu" signal "GND3")
		(18 "In8.Cu" signal "VCC")
		(20 "In9.Cu" signal "VCC1")
		(22 "In10.Cu" signal "GND4")
		(24 "In11.Cu" signal "IN4")
		(26 "In12.Cu" signal "GND5")
		(28 "In13.Cu" signal "IN5")
		(30 "In14.Cu" signal "GND6")
		(32 "In15.Cu" signal "IN6")
		(34 "In16.Cu" signal "GND7")
		(2 "B.Cu" signal "BOTTOM")
		(9 "F.Adhes" user "F.Adhesive")
		(11 "B.Adhes" user "B.Adhesive")
		(13 "F.Paste" user "Package Geometry/Pastemask Top")
		(15 "B.Paste" user "Package Geometry/Pastemask Bottom")
		(5 "F.SilkS" user "Ref Des/Silkscreen Top")
		(7 "B.SilkS" user "Ref Des/Silkscreen Bottom")
		(1 "F.Mask" user "Board Geometry/Soldermask Top")
		(3 "B.Mask" user "Board Geometry/Soldermask Bottom")
		(17 "Dwgs.User" user "User.Drawings")
		(19 "Cmts.User" user "User.Comments")
		(21 "Eco1.User" user "User.Eco1")
		(23 "Eco2.User" user "User.Eco2")
		(25 "Edge.Cuts" user "Board Geometry/Outline")
		(27 "Margin" user)
		(31 "F.CrtYd" user "Package Geometry/Place Bound Top")
		(29 "B.CrtYd" user "Package Geometry/Place Bound Bottom")
		(35 "F.Fab" user "Ref Des/Assembly Top")
		(33 "B.Fab" user "Ref Des/Assembly Bottom")
	)
	(footprint ""
		(layer "F.Cu")
		(at 107.975146 -99.609402)
		(property "Reference" "Q86"
			(at 2.133854 -1.933956 0)
			(unlocked yes)
			(layer "F.SilkS")
			(effects
				(font
					(size 0.7874 0.5842)
					(thickness 0.1524)
				)
				(justify left)
			)
		)
		(property "Value" ""
			(at 0 0 0)
			(layer "F.Fab")
			(effects
				(font
					(size 1.27 1.27)
				)
			)
		)
		(duplicate_pad_numbers_are_jumpers no)
		(fp_line
			(start -1.332738 -1.100074)
			(end -0.4826 -1.100074)
			(stroke
				(width 0.1524)
				(type default)
			)
			(layer "F.SilkS")
		)
		(fp_line
			(start -1.332738 1.100074)
			(end -1.332738 -1.100074)
			(stroke
				(width 0.1524)
				(type default)
			)
			(layer "F.SilkS")
		)
		(fp_line
			(start -0.4826 -1.100074)
			(end 0 -0.541274)
			(stroke
				(width 0.1524)
				(type default)
			)
			(layer "F.SilkS")
		)
		(fp_line
			(start 0 -0.541274)
			(end 0.4826 -1.100074)
			(stroke
				(width 0.1524)
				(type default)
			)
			(layer "F.SilkS")
		)
		(fp_line
			(start 0.4826 -1.100074)
			(end 1.332738 -1.100074)
			(stroke
				(width 0.1524)
				(type default)
			)
			(layer "F.SilkS")
		)
		(fp_line
			(start 1.332738 -1.100074)
			(end 1.332738 1.100074)
			(stroke
				(width 0.1524)
				(type default)
			)
			(layer "F.SilkS")
		)
		(fp_line
			(start 1.332738 1.100074)
			(end -1.332738 1.100074)
			(stroke
				(width 0.1524)
				(type default)
			)
			(layer "F.SilkS")
		)
		(fp_poly
			(pts
				(xy -0.634238 -1.97358) (xy -0.985266 -1.271524) (xy -1.336294 -1.97358)
			)
			(stroke
				(width 0)
				(type default)
			)
			(fill yes)
			(layer "F.SilkS")
		)
		(fp_line
			(start -0.674878 -1.100074)
			(end 0.674878 -1.100074)
			(stroke
				(width 0.1)
				(type default)
			)
			(layer "F.Fab")
		)
		(fp_line
			(start -0.674878 1.100074)
			(end -0.674878 -1.100074)
			(stroke
				(width 0.1)
				(type default)
			)
			(layer "F.Fab")
		)
		(fp_line
			(start 0.674878 -1.100074)
			(end 0.674878 1.100074)
			(stroke
				(width 0.1)
				(type default)
			)
			(layer "F.Fab")
		)
		(fp_line
			(start 0.674878 1.100074)
			(end -0.674878 1.100074)
			(stroke
				(width 0.1)
				(type default)
			)
			(layer "F.Fab")
		)
		(fp_poly
			(pts
				(xy -2.2352 -0.298958) (xy -2.2352 -1.001014) (xy -1.533144 -0.649986)
			)
			(stroke
				(width 0)
				(type default)
			)
			(fill yes)
			(layer "F.Fab")
		)
		(pad "1" smd rect
			(at -0.94996 -0.649986 90)
			(size 0.4318 0.508)
			(layers "F.Cu" "F.Mask" "F.Paste")
			(net "GND")
		)
		(pad "2" smd rect
			(at -0.94996 0 90)
			(size 0.4318 0.508)
			(layers "F.Cu" "F.Mask" "F.Paste")
			(net "PWRGD_PVCCINFAON_CPU1")
		)
		(pad "3" smd rect
			(at -0.94996 0.649986 90)
			(size 0.4318 0.508)
			(layers "F.Cu" "F.Mask" "F.Paste")
			(net "LED_PWRGD_PVNN_MAIN_CPU1_D")
		)
		(pad "4" smd rect
			(at 0.94996 0.649986 90)
			(size 0.4318 0.508)
			(layers "F.Cu" "F.Mask" "F.Paste")
			(net "GND")
		)
		(pad "5" smd rect
			(at 0.94996 0 90)
			(size 0.4318 0.508)
			(layers "F.Cu" "F.Mask" "F.Paste")
			(net "PWRGD_PVNN_MAIN_CPU1")
		)
		(pad "6" smd rect
			(at 0.94996 -0.649986 90)
			(size 0.4318 0.508)
			(layers "F.Cu" "F.Mask" "F.Paste")
			(net "LED_PWRGD_PVCCINFAON_CPU1_D")
		)
	)
	(footprint ""
		(layer "F.Cu")
		(at 101.219 -40.231568)
		(property "Reference" "U207"
			(at -1.778 -1.819148 0)
			(unlocked yes)
			(layer "F.SilkS")
			(effects
				(font
					(size 0.7874 0.5842)
					(thickness 0.1524)
				)
				(justify left)
			)
		)
		(property "Value" ""
			(at 0 0 0)
			(layer "F.Fab")
			(effects
				(font
					(size 1.27 1.27)
				)
			)
		)
		(duplicate_pad_numbers_are_jumpers no)
		(fp_line
			(start -1.695958 -1.124966)
			(end 1.695958 -1.124966)
			(stroke
				(width 0.1524)
				(type default)
			)
			(layer "F.SilkS")
		)
		(fp_line
			(start -1.695958 1.124966)
			(end -1.695958 -1.124966)
			(stroke
				(width 0.1524)
				(type default)
			)
			(layer "F.SilkS")
		)
		(fp_line
			(start 1.695958 -1.124966)
			(end 1.695958 1.124966)
			(stroke
				(width 0.1524)
				(type default)
			)
			(layer "F.SilkS")
		)
		(fp_line
			(start 1.695958 1.124966)
			(end -1.695958 1.124966)
			(stroke
				(width 0.1524)
				(type default)
			)
			(layer "F.SilkS")
		)
		(fp_poly
			(pts
				(xy -1.96342 -0.680466) (xy -2.58318 -0.370586) (xy -2.58318 -0.990346)
			)
			(stroke
				(width 0)
				(type default)
			)
			(fill yes)
			(layer "F.SilkS")
		)
		(fp_line
			(start -0.674878 -1.124966)
			(end 0.674878 -1.124966)
			(stroke
				(width 0.1)
				(type default)
			)
			(layer "F.Fab")
		)
		(fp_line
			(start -0.674878 1.124966)
			(end -0.674878 -1.124966)
			(stroke
				(width 0.1)
				(type default)
			)
			(layer "F.Fab")
		)
		(fp_line
			(start 0.674878 -1.124966)
			(end 0.674878 1.124966)
			(stroke
				(width 0.1)
				(type default)
			)
			(layer "F.Fab")
		)
		(fp_line
			(start 0.674878 1.124966)
			(end -0.674878 1.124966)
			(stroke
				(width 0.1)
				(type default)
			)
			(layer "F.Fab")
		)
		(fp_poly
			(pts
				(xy -2.4892 -0.959866) (xy -1.86944 -0.649986) (xy -2.4892 -0.340106)
			)
			(stroke
				(width 0)
				(type default)
			)
			(fill yes)
			(layer "F.Fab")
		)
		(pad "1" smd rect
			(at -0.94488 -0.649986 90)
			(size 0.3556 1.2446)
			(layers "F.Cu" "F.Mask" "F.Paste")
			(net "Net_1690")
		)
		(pad "2" smd rect
			(at -0.94488 0 90)
			(size 0.3556 1.2446)
			(layers "F.Cu" "F.Mask" "F.Paste")
			(net "RST_HP_OCP_V3_2_N")
		)
		(pad "3" smd rect
			(at -0.94488 0.649986 90)
			(size 0.3556 1.2446)
			(layers "F.Cu" "F.Mask" "F.Paste")
			(net "GND")
		)
		(pad "4" smd rect
			(at 0.94488 0.649986 90)
			(size 0.3556 1.2446)
			(layers "F.Cu" "F.Mask" "F.Paste")
			(net "RST_OCP_V3_2_BUF_N")
		)
		(pad "5" smd rect
			(at 0.94488 -0.649986 90)
			(size 0.3556 1.2446)
			(layers "F.Cu" "F.Mask" "F.Paste")
			(net "P3V3_AUX")
		)
	)
)
